(kicad_pcb
	(version 20260206)
	(generator "pcbnew")
	(generator_version "10.0")
	(general
		(thickness 1.6)
		(legacy_teardrops no)
	)
	(paper "A4")
	(title_block
		(title "01162023_DA0F0TEBIF0_F0T_Expander_BD_F_brd_V02_OCP.brd")
		(comment 1 "Grand Teton / footprints 7435-7442 of 9728")
	)
	(layers
		(0 "F.Cu" signal "TOP")
		(4 "In1.Cu" signal "GND")
		(6 "In2.Cu" signal "VCC")
		(8 "In3.Cu" signal "VCC1")
		(10 "In4.Cu" signal "GND1")
		(12 "In5.Cu" signal "IN1")
		(14 "In6.Cu" signal "GND2")
		(16 "In7.Cu" signal "IN2")
		(18 "In8.Cu" signal "GND3")
		(20 "In9.Cu" signal "IN3")
		(22 "In10.Cu" signal "GND4")
		(24 "In11.Cu" signal "IN4")
		(26 "In12.Cu" signal "GND5")
		(28 "In13.Cu" signal "IN5")
		(30 "In14.Cu" signal "GND6")
		(32 "In15.Cu" signal "IN6")
		(34 "In16.Cu" signal "GND7")
		(2 "B.Cu" signal "BOTTOM")
		(9 "F.Adhes" user "F.Adhesive")
		(11 "B.Adhes" user "B.Adhesive")
		(13 "F.Paste" user "Package Geometry/Pastemask Top")
		(15 "B.Paste" user "Package Geometry/Pastemask Bottom")
		(5 "F.SilkS" user "Ref Des/Silkscreen Top")
		(7 "B.SilkS" user "Ref Des/Silkscreen Bottom")
		(1 "F.Mask" user "Board Geometry/Soldermask Top")
		(3 "B.Mask" user "Board Geometry/Soldermask Bottom")
		(17 "Dwgs.User" user "User.Drawings")
		(19 "Cmts.User" user "User.Comments")
		(21 "Eco1.User" user "User.Eco1")
		(23 "Eco2.User" user "User.Eco2")
		(25 "Edge.Cuts" user "Board Geometry/Outline")
		(27 "Margin" user)
		(31 "F.CrtYd" user "Package Geometry/Place Bound Top")
		(29 "B.CrtYd" user "Package Geometry/Place Bound Bottom")
		(35 "F.Fab" user "Ref Des/Assembly Top")
		(33 "B.Fab" user "Ref Des/Assembly Bottom")
	)
	(footprint ""
		(layer "B.Cu")
		(at 379.365002 -223.733106)
		(property "Reference" "R929"
			(at 0 0 0)
			(layer "B.SilkS")
			(hide yes)
			(effects
				(font
					(size 1.27 1.27)
				)
				(justify mirror)
			)
		)
		(property "Value" ""
			(at 0 0 0)
			(layer "B.Fab")
			(effects
				(font
					(size 1.27 1.27)
				)
				(justify mirror)
			)
		)
		(duplicate_pad_numbers_are_jumpers no)
		(fp_line
			(start -0.7874 -0.4064)
			(end -0.7874 0.4064)
			(stroke
				(width 0.1524)
				(type default)
			)
			(layer "B.SilkS")
		)
		(fp_line
			(start -0.7874 0.4064)
			(end 0.7874 0.4064)
			(stroke
				(width 0.1524)
				(type default)
			)
			(layer "B.SilkS")
		)
		(fp_line
			(start 0.7874 -0.4064)
			(end -0.7874 -0.4064)
			(stroke
				(width 0.1524)
				(type default)
			)
			(layer "B.SilkS")
		)
		(fp_line
			(start 0.7874 0.4064)
			(end 0.7874 -0.4064)
			(stroke
				(width 0.1524)
				(type default)
			)
			(layer "B.SilkS")
		)
		(fp_line
			(start -0.67945 -0.3048)
			(end -0.67945 0.3048)
			(stroke
				(width 0.1)
				(type default)
			)
			(layer "B.Fab")
		)
		(fp_line
			(start -0.67945 0.3048)
			(end -0.120396 0.3048)
			(stroke
				(width 0.1)
				(type default)
			)
			(layer "B.Fab")
		)
		(fp_line
			(start -0.12065 -0.3048)
			(end -0.67945 -0.3048)
			(stroke
				(width 0.1)
				(type default)
			)
			(layer "B.Fab")
		)
		(fp_line
			(start -0.12065 -0.2794)
			(end -0.12065 -0.3048)
			(stroke
				(width 0.1)
				(type default)
			)
			(layer "B.Fab")
		)
		(fp_line
			(start -0.120396 0.2794)
			(end 0.12065 0.2794)
			(stroke
				(width 0.1)
				(type default)
			)
			(layer "B.Fab")
		)
		(fp_line
			(start -0.120396 0.3048)
			(end -0.120396 0.2794)
			(stroke
				(width 0.1)
				(type default)
			)
			(layer "B.Fab")
		)
		(fp_line
			(start 0.12065 -0.305054)
			(end 0.12065 -0.2794)
			(stroke
				(width 0.1)
				(type default)
			)
			(layer "B.Fab")
		)
		(fp_line
			(start 0.12065 -0.2794)
			(end -0.12065 -0.2794)
			(stroke
				(width 0.1)
				(type default)
			)
			(layer "B.Fab")
		)
		(fp_line
			(start 0.12065 0.2794)
			(end 0.12065 0.3048)
			(stroke
				(width 0.1)
				(type default)
			)
			(layer "B.Fab")
		)
		(fp_line
			(start 0.12065 0.3048)
			(end 0.67945 0.3048)
			(stroke
				(width 0.1)
				(type default)
			)
			(layer "B.Fab")
		)
		(fp_line
			(start 0.67945 -0.305054)
			(end 0.12065 -0.305054)
			(stroke
				(width 0.1)
				(type default)
			)
			(layer "B.Fab")
		)
		(fp_line
			(start 0.67945 0.3048)
			(end 0.67945 -0.305054)
			(stroke
				(width 0.1)
				(type default)
			)
			(layer "B.Fab")
		)
		(pad "1" smd circle
			(at 0.40005 0 180)
			(size 0 0)
			(layers "B.Cu" "B.Mask" "B.Paste")
			(net "UART_PEX0_SDB_BUF_R_RX")
		)
		(pad "2" smd circle
			(at -0.40005 0 180)
			(size 0 0)
			(layers "B.Cu" "B.Mask" "B.Paste")
			(net "UART_PEX0_SDB_BUF_RX")
		)
	)
	(footprint ""
		(layer "B.Cu")
		(at 66.801238 -305.399948 -90)
		(property "Reference" "C2962"
			(at 0 0 90)
			(layer "B.SilkS")
			(hide yes)
			(effects
				(font
					(size 1.27 1.27)
				)
				(justify mirror)
			)
		)
		(property "Value" ""
			(at 0 0 90)
			(layer "B.Fab")
			(effects
				(font
					(size 1.27 1.27)
				)
				(justify mirror)
			)
		)
		(duplicate_pad_numbers_are_jumpers no)
		(fp_line
			(start -0.299974 0.150114)
			(end 0.299974 0.150114)
			(stroke
				(width 0.1)
				(type default)
			)
			(layer "B.Fab")
		)
		(fp_line
			(start 0.299974 0.150114)
			(end 0.299974 -0.150114)
			(stroke
				(width 0.1)
				(type default)
			)
			(layer "B.Fab")
		)
		(fp_line
			(start -0.299974 -0.150114)
			(end -0.299974 0.150114)
			(stroke
				(width 0.1)
				(type default)
			)
			(layer "B.Fab")
		)
		(fp_line
			(start 0.299974 -0.150114)
			(end -0.299974 -0.150114)
			(stroke
				(width 0.1)
				(type default)
			)
			(layer "B.Fab")
		)
		(pad "1" smd rect
			(at 0.2667 0 90)
			(size 0.3048 0.381)
			(layers "B.Cu" "B.Mask" "B.Paste")
			(net "P1V25_SERDES_VDDPLL_PEX0")
		)
		(pad "2" smd rect
			(at -0.2667 0 90)
			(size 0.3048 0.381)
			(layers "B.Cu" "B.Mask" "B.Paste")
			(net "GND")
		)
	)
	(footprint ""
		(layer "B.Cu")
		(at 341.978234 -326.945498 -90)
		(property "Reference" "C4314"
			(at 0 0 90)
			(layer "B.SilkS")
			(hide yes)
			(effects
				(font
					(size 1.27 1.27)
				)
				(justify mirror)
			)
		)
		(property "Value" ""
			(at 0 0 90)
			(layer "B.Fab")
			(effects
				(font
					(size 1.27 1.27)
				)
				(justify mirror)
			)
		)
		(duplicate_pad_numbers_are_jumpers no)
		(fp_line
			(start -1.2954 0.5842)
			(end 1.2954 0.5842)
			(stroke
				(width 0.1524)
				(type default)
			)
			(layer "B.SilkS")
		)
		(fp_line
			(start 1.2954 0.5842)
			(end 1.2954 -0.5842)
			(stroke
				(width 0.1524)
				(type default)
			)
			(layer "B.SilkS")
		)
		(fp_line
			(start -1.2954 -0.5842)
			(end -1.2954 0.5842)
			(stroke
				(width 0.1524)
				(type default)
			)
			(layer "B.SilkS")
		)
		(fp_line
			(start 1.2954 -0.5842)
			(end -1.2954 -0.5842)
			(stroke
				(width 0.1524)
				(type default)
			)
			(layer "B.SilkS")
		)
		(fp_line
			(start -0.8636 0.4572)
			(end 0.8636 0.4572)
			(stroke
				(width 0.1)
				(type default)
			)
			(layer "B.Fab")
		)
		(fp_line
			(start 0.8636 0.4572)
			(end 0.8636 0.4064)
			(stroke
				(width 0.1)
				(type default)
			)
			(layer "B.Fab")
		)
		(fp_line
			(start -1.1938 0.4064)
			(end -0.8636 0.4064)
			(stroke
				(width 0.1)
				(type default)
			)
			(layer "B.Fab")
		)
		(fp_line
			(start -0.8636 0.4064)
			(end -0.8636 0.4572)
			(stroke
				(width 0.1)
				(type default)
			)
			(layer "B.Fab")
		)
		(fp_line
			(start 0.8636 0.4064)
			(end 1.1938 0.4064)
			(stroke
				(width 0.1)
				(type default)
			)
			(layer "B.Fab")
		)
		(fp_line
			(start 1.1938 0.4064)
			(end 1.1938 -0.4064)
			(stroke
				(width 0.1)
				(type default)
			)
			(layer "B.Fab")
		)
		(fp_line
			(start -1.1938 -0.4064)
			(end -1.1938 0.4064)
			(stroke
				(width 0.1)
				(type default)
			)
			(layer "B.Fab")
		)
		(fp_line
			(start -0.8636 -0.4064)
			(end -1.1938 -0.4064)
			(stroke
				(width 0.1)
				(type default)
			)
			(layer "B.Fab")
		)
		(fp_line
			(start 0.8636 -0.4064)
			(end 0.8636 -0.4572)
			(stroke
				(width 0.1)
				(type default)
			)
			(layer "B.Fab")
		)
		(fp_line
			(start 1.1938 -0.4064)
			(end 0.8636 -0.4064)
			(stroke
				(width 0.1)
				(type default)
			)
			(layer "B.Fab")
		)
		(fp_line
			(start -0.8636 -0.4572)
			(end -0.8636 -0.4064)
			(stroke
				(width 0.1)
				(type default)
			)
			(layer "B.Fab")
		)
		(fp_line
			(start 0.8636 -0.4572)
			(end -0.8636 -0.4572)
			(stroke
				(width 0.1)
				(type default)
			)
			(layer "B.Fab")
		)
		(pad "1" smd rect
			(at 0.7366 0 180)
			(size 0.7112 0.8128)
			(layers "B.Cu" "B.Mask" "B.Paste")
			(net "P0V8_SERDES_VDDA_PEX2_C4")
		)
		(pad "2" smd rect
			(at -0.7366 0 180)
			(size 0.7112 0.8128)
			(layers "B.Cu" "B.Mask" "B.Paste")
			(net "GND")
		)
	)
	(footprint ""
		(layer "B.Cu")
		(at 408.424888 -293.99992 -90)
		(property "Reference" "C1920"
			(at 0 0 90)
			(layer "B.SilkS")
			(hide yes)
			(effects
				(font
					(size 1.27 1.27)
				)
				(justify mirror)
			)
		)
		(property "Value" ""
			(at 0 0 90)
			(layer "B.Fab")
			(effects
				(font
					(size 1.27 1.27)
				)
				(justify mirror)
			)
		)
		(duplicate_pad_numbers_are_jumpers no)
		(fp_line
			(start -0.299974 0.150114)
			(end 0.299974 0.150114)
			(stroke
				(width 0.1)
				(type default)
			)
			(layer "B.Fab")
		)
		(fp_line
			(start 0.299974 0.150114)
			(end 0.299974 -0.150114)
			(stroke
				(width 0.1)
				(type default)
			)
			(layer "B.Fab")
		)
		(fp_line
			(start -0.299974 -0.150114)
			(end -0.299974 0.150114)
			(stroke
				(width 0.1)
				(type default)
			)
			(layer "B.Fab")
		)
		(fp_line
			(start 0.299974 -0.150114)
			(end -0.299974 -0.150114)
			(stroke
				(width 0.1)
				(type default)
			)
			(layer "B.Fab")
		)
		(pad "1" smd rect
			(at 0.2667 0 90)
			(size 0.3048 0.381)
			(layers "B.Cu" "B.Mask" "B.Paste")
			(net "P0V8_PEX3")
		)
		(pad "2" smd rect
			(at -0.2667 0 90)
			(size 0.3048 0.381)
			(layers "B.Cu" "B.Mask" "B.Paste")
			(net "GND")
		)
	)
	(footprint ""
		(layer "B.Cu")
		(at 388.202678 -247.165114 -90)
		(property "Reference" "R941"
			(at 0 0 90)
			(layer "B.SilkS")
			(hide yes)
			(effects
				(font
					(size 1.27 1.27)
				)
				(justify mirror)
			)
		)
		(property "Value" ""
			(at 0 0 90)
			(layer "B.Fab")
			(effects
				(font
					(size 1.27 1.27)
				)
				(justify mirror)
			)
		)
		(duplicate_pad_numbers_are_jumpers no)
		(fp_line
			(start -0.7874 0.4064)
			(end 0.7874 0.4064)
			(stroke
				(width 0.1524)
				(type default)
			)
			(layer "B.SilkS")
		)
		(fp_line
			(start 0.7874 0.4064)
			(end 0.7874 -0.4064)
			(stroke
				(width 0.1524)
				(type default)
			)
			(layer "B.SilkS")
		)
		(fp_line
			(start -0.7874 -0.4064)
			(end -0.7874 0.4064)
			(stroke
				(width 0.1524)
				(type default)
			)
			(layer "B.SilkS")
		)
		(fp_line
			(start 0.7874 -0.4064)
			(end -0.7874 -0.4064)
			(stroke
				(width 0.1524)
				(type default)
			)
			(layer "B.SilkS")
		)
		(fp_line
			(start -0.67945 0.3048)
			(end -0.120396 0.3048)
			(stroke
				(width 0.1)
				(type default)
			)
			(layer "B.Fab")
		)
		(fp_line
			(start -0.120396 0.3048)
			(end -0.120396 0.2794)
			(stroke
				(width 0.1)
				(type default)
			)
			(layer "B.Fab")
		)
		(fp_line
			(start 0.12065 0.3048)
			(end 0.67945 0.3048)
			(stroke
				(width 0.1)
				(type default)
			)
			(layer "B.Fab")
		)
		(fp_line
			(start 0.67945 0.3048)
			(end 0.67945 -0.305054)
			(stroke
				(width 0.1)
				(type default)
			)
			(layer "B.Fab")
		)
		(fp_line
			(start -0.120396 0.2794)
			(end 0.12065 0.2794)
			(stroke
				(width 0.1)
				(type default)
			)
			(layer "B.Fab")
		)
		(fp_line
			(start 0.12065 0.2794)
			(end 0.12065 0.3048)
			(stroke
				(width 0.1)
				(type default)
			)
			(layer "B.Fab")
		)
		(fp_line
			(start -0.12065 -0.2794)
			(end -0.12065 -0.3048)
			(stroke
				(width 0.1)
				(type default)
			)
			(layer "B.Fab")
		)
		(fp_line
			(start 0.12065 -0.2794)
			(end -0.12065 -0.2794)
			(stroke
				(width 0.1)
				(type default)
			)
			(layer "B.Fab")
		)
		(fp_line
			(start -0.67945 -0.3048)
			(end -0.67945 0.3048)
			(stroke
				(width 0.1)
				(type default)
			)
			(layer "B.Fab")
		)
		(fp_line
			(start -0.12065 -0.3048)
			(end -0.67945 -0.3048)
			(stroke
				(width 0.1)
				(type default)
			)
			(layer "B.Fab")
		)
		(fp_line
			(start 0.12065 -0.305054)
			(end 0.12065 -0.2794)
			(stroke
				(width 0.1)
				(type default)
			)
			(layer "B.Fab")
		)
		(fp_line
			(start 0.67945 -0.305054)
			(end 0.12065 -0.305054)
			(stroke
				(width 0.1)
				(type default)
			)
			(layer "B.Fab")
		)
		(pad "1" smd circle
			(at 0.40005 0 90)
			(size 0 0)
			(layers "B.Cu" "B.Mask" "B.Paste")
			(net "UART_PEX2_SDB_BUF_R_RX")
		)
		(pad "2" smd circle
			(at -0.40005 0 90)
			(size 0 0)
			(layers "B.Cu" "B.Mask" "B.Paste")
			(net "UART_PEX2_SDB_BUF_RX")
		)
	)
	(footprint ""
		(layer "B.Cu")
		(at 44.449746 -292.099746)
		(property "Reference" "C2999"
			(at 0 0 0)
			(layer "B.SilkS")
			(hide yes)
			(effects
				(font
					(size 1.27 1.27)
				)
				(justify mirror)
			)
		)
		(property "Value" ""
			(at 0 0 0)
			(layer "B.Fab")
			(effects
				(font
					(size 1.27 1.27)
				)
				(justify mirror)
			)
		)
		(duplicate_pad_numbers_are_jumpers no)
		(fp_line
			(start -0.299974 -0.150114)
			(end -0.299974 0.150114)
			(stroke
				(width 0.1)
				(type default)
			)
			(layer "B.Fab")
		)
		(fp_line
			(start -0.299974 0.150114)
			(end 0.299974 0.150114)
			(stroke
				(width 0.1)
				(type default)
			)
			(layer "B.Fab")
		)
		(fp_line
			(start 0.299974 -0.150114)
			(end -0.299974 -0.150114)
			(stroke
				(width 0.1)
				(type default)
			)
			(layer "B.Fab")
		)
		(fp_line
			(start 0.299974 0.150114)
			(end 0.299974 -0.150114)
			(stroke
				(width 0.1)
				(type default)
			)
			(layer "B.Fab")
		)
		(pad "1" smd rect
			(at 0.2667 0 180)
			(size 0.3048 0.381)
			(layers "B.Cu" "B.Mask" "B.Paste")
			(net "P1V8_PEX")
		)
		(pad "2" smd rect
			(at -0.2667 0 180)
			(size 0.3048 0.381)
			(layers "B.Cu" "B.Mask" "B.Paste")
			(net "GND")
		)
	)
	(footprint ""
		(layer "B.Cu")
		(at 116.788184 -318.542416 180)
		(property "Reference" "C4209"
			(at 0 0 0)
			(layer "B.SilkS")
			(hide yes)
			(effects
				(font
					(size 1.27 1.27)
				)
				(justify mirror)
			)
		)
		(property "Value" ""
			(at 0 0 0)
			(layer "B.Fab")
			(effects
				(font
					(size 1.27 1.27)
				)
				(justify mirror)
			)
		)
		(duplicate_pad_numbers_are_jumpers no)
		(fp_line
			(start 0.299974 0.150114)
			(end 0.299974 -0.150114)
			(stroke
				(width 0.1)
				(type default)
			)
			(layer "B.Fab")
		)
		(fp_line
			(start 0.299974 -0.150114)
			(end -0.299974 -0.150114)
			(stroke
				(width 0.1)
				(type default)
			)
			(layer "B.Fab")
		)
		(fp_line
			(start -0.299974 0.150114)
			(end 0.299974 0.150114)
			(stroke
				(width 0.1)
				(type default)
			)
			(layer "B.Fab")
		)
		(fp_line
			(start -0.299974 -0.150114)
			(end -0.299974 0.150114)
			(stroke
				(width 0.1)
				(type default)
			)
			(layer "B.Fab")
		)
		(pad "1" smd rect
			(at 0.2667 0)
			(size 0.3048 0.381)
			(layers "B.Cu" "B.Mask" "B.Paste")
			(net "P0V8_SERDES_VDDA_PEX0")
		)
		(pad "2" smd rect
			(at -0.2667 0)
			(size 0.3048 0.381)
			(layers "B.Cu" "B.Mask" "B.Paste")
			(net "GND")
		)
	)
	(footprint ""
		(layer "B.Cu")
		(at 103.764842 -337.475576 -90)
		(property "Reference" "C2697"
			(at 0 0 90)
			(layer "B.SilkS")
			(hide yes)
			(effects
				(font
					(size 1.27 1.27)
				)
				(justify mirror)
			)
		)
		(property "Value" ""
			(at 0 0 90)
			(layer "B.Fab")
			(effects
				(font
					(size 1.27 1.27)
				)
				(justify mirror)
			)
		)
		(duplicate_pad_numbers_are_jumpers no)
		(fp_line
			(start -0.7874 0.4064)
			(end 0.7874 0.4064)
			(stroke
				(width 0.1524)
				(type default)
			)
			(layer "B.SilkS")
		)
		(fp_line
			(start 0.7874 0.4064)
			(end 0.7874 -0.4064)
			(stroke
				(width 0.1524)
				(type default)
			)
			(layer "B.SilkS")
		)
		(fp_line
			(start -0.7874 -0.4064)
			(end -0.7874 0.4064)
			(stroke
				(width 0.1524)
				(type default)
			)
			(layer "B.SilkS")
		)
		(fp_line
			(start 0.7874 -0.4064)
			(end -0.7874 -0.4064)
			(stroke
				(width 0.1524)
				(type default)
			)
			(layer "B.SilkS")
		)
		(fp_line
			(start -0.67945 0.3048)
			(end -0.120396 0.3048)
			(stroke
				(width 0.1)
				(type default)
			)
			(layer "B.Fab")
		)
		(fp_line
			(start -0.120396 0.3048)
			(end -0.120396 0.2794)
			(stroke
				(width 0.1)
				(type default)
			)
			(layer "B.Fab")
		)
		(fp_line
			(start 0.12065 0.3048)
			(end 0.67945 0.3048)
			(stroke
				(width 0.1)
				(type default)
			)
			(layer "B.Fab")
		)
		(fp_line
			(start 0.67945 0.3048)
			(end 0.67945 -0.305054)
			(stroke
				(width 0.1)
				(type default)
			)
			(layer "B.Fab")
		)
		(fp_line
			(start -0.120396 0.2794)
			(end 0.12065 0.2794)
			(stroke
				(width 0.1)
				(type default)
			)
			(layer "B.Fab")
		)
		(fp_line
			(start 0.12065 0.2794)
			(end 0.12065 0.3048)
			(stroke
				(width 0.1)
				(type default)
			)
			(layer "B.Fab")
		)
		(fp_line
			(start -0.12065 -0.2794)
			(end -0.12065 -0.3048)
			(stroke
				(width 0.1)
				(type default)
			)
			(layer "B.Fab")
		)
		(fp_line
			(start 0.12065 -0.2794)
			(end -0.12065 -0.2794)
			(stroke
				(width 0.1)
				(type default)
			)
			(layer "B.Fab")
		)
		(fp_line
			(start -0.67945 -0.3048)
			(end -0.67945 0.3048)
			(stroke
				(width 0.1)
				(type default)
			)
			(layer "B.Fab")
		)
		(fp_line
			(start -0.12065 -0.3048)
			(end -0.67945 -0.3048)
			(stroke
				(width 0.1)
				(type default)
			)
			(layer "B.Fab")
		)
		(fp_line
			(start 0.12065 -0.305054)
			(end 0.12065 -0.2794)
			(stroke
				(width 0.1)
				(type default)
			)
			(layer "B.Fab")
		)
		(fp_line
			(start 0.67945 -0.305054)
			(end 0.12065 -0.305054)
			(stroke
				(width 0.1)
				(type default)
			)
			(layer "B.Fab")
		)
		(pad "1" smd circle
			(at 0.40005 0 90)
			(size 0 0)
			(layers "B.Cu" "B.Mask" "B.Paste")
			(net "P3V3_CLK_BUFFER_9ZXL0451E_VZX3P3")
		)
		(pad "2" smd circle
			(at -0.40005 0 90)
			(size 0 0)
			(layers "B.Cu" "B.Mask" "B.Paste")
			(net "GND")
		)
	)
)
